# BASEBOARD_FAB2 (Tioga Pass) — schematic netlist excerpt (pin names and nets, part order shuffled) for the footprints in the layout excerpt that follows; sources: Cadence DE-HDL packaged netlist, KiCad conversion of Wiwynn_Tioga_Pass_MB.brd

C1D17  CAP  1.0UF 16V 10% X6S  pkg 0402  page 208 : A = VR_PVCCIN_CPU1_PH3_VCIN ; B = GND

EU1E3  MOSFETN_1D3S  IC  pkg SOT5  page 200
  S1  = P12V_STBY
  S2  = P12V_STBY
  S3  = P12V_STBY
  G  = A_HSC_GATE1_R
  D  = P12V_MB0_SW

(kicad_pcb
	(version 20260206)
	(generator "pcbnew")
	(generator_version "10.0")
	(general
		(thickness 1.6)
		(legacy_teardrops no)
	)
	(paper "A4")
	(title_block
		(title "Wiwynn_Tioga_Pass_MB.brd")
		(comment 1 "Tioga Pass / footprints 1276-1277 of 4770")
	)
	(layers
		(0 "F.Cu" signal "TOP")
		(4 "In1.Cu" signal "L2GND")
		(6 "In2.Cu" signal "L3")
		(8 "In3.Cu" signal "L4GND")
		(10 "In4.Cu" signal "L5")
		(12 "In5.Cu" signal "L6GND")
		(14 "In6.Cu" signal "L7VCC")
		(16 "In7.Cu" signal "L8VCC")
		(18 "In8.Cu" signal "L9GND")
		(20 "In9.Cu" signal "L10")
		(22 "In10.Cu" signal "L11GND")
		(24 "In11.Cu" signal "L12")
		(26 "In12.Cu" signal "L13GND")
		(2 "B.Cu" signal "BOTTOM")
		(9 "F.Adhes" user "F.Adhesive")
		(11 "B.Adhes" user "B.Adhesive")
		(13 "F.Paste" user "Package Geometry/Pastemask Top")
		(15 "B.Paste" user "Package Geometry/Pastemask Bottom")
		(5 "F.SilkS" user "Ref Des/Silkscreen Top")
		(7 "B.SilkS" user "Ref Des/Silkscreen Bottom")
		(1 "F.Mask" user "Board Geometry/Soldermask Top")
		(3 "B.Mask" user "Board Geometry/Soldermask Bottom")
		(17 "Dwgs.User" user "User.Drawings")
		(19 "Cmts.User" user "User.Comments")
		(21 "Eco1.User" user "User.Eco1")
		(23 "Eco2.User" user "User.Eco2")
		(25 "Edge.Cuts" user "Board Geometry/Outline")
		(27 "Margin" user)
		(31 "F.CrtYd" user "Package Geometry/Place Bound Top")
		(29 "B.CrtYd" user "Package Geometry/Place Bound Bottom")
		(35 "F.Fab" user "Ref Des/Assembly Top")
		(33 "B.Fab" user "Ref Des/Assembly Bottom")
	)
	(footprint ""
		(layer "F.Cu")
		(at 32.416496 -69.223382 -90)
		(property "Reference" "C1D17"
			(at 0 0 270)
			(layer "F.SilkS")
			(hide yes)
			(effects
				(font
					(size 1.27 1.27)
				)
			)
		)
		(property "Value" ""
			(at 0 0 270)
			(layer "F.Fab")
			(effects
				(font
					(size 1.27 1.27)
				)
			)
		)
		(duplicate_pad_numbers_are_jumpers no)
		(fp_rect
			(start 0.3048 0.9906)
			(end -0.3048 -0.1016)
			(stroke
				(width 0)
				(type default)
			)
			(fill no)
			(layer "F.CrtYd")
		)
		(fp_line
			(start -0.3048 0.9906)
			(end 0.3048 0.9906)
			(stroke
				(width 0.1)
				(type default)
			)
			(layer "F.Fab")
		)
		(fp_line
			(start 0.3048 0.9906)
			(end 0.3048 -0.1016)
			(stroke
				(width 0.1)
				(type default)
			)
			(layer "F.Fab")
		)
		(fp_line
			(start -0.3048 -0.1016)
			(end -0.3048 0.9906)
			(stroke
				(width 0.1)
				(type default)
			)
			(layer "F.Fab")
		)
		(fp_line
			(start 0.3048 -0.1016)
			(end -0.3048 -0.1016)
			(stroke
				(width 0.1)
				(type default)
			)
			(layer "F.Fab")
		)
		(pad "1" smd rect
			(at 0 0 270)
			(size 0.508 0.508)
			(layers "F.Cu" "F.Mask" "F.Paste")
			(net "VR_PVCCIN_CPU1_PH3_VCIN")
		)
		(pad "2" smd rect
			(at 0 0.889 270)
			(size 0.508 0.508)
			(layers "F.Cu" "F.Mask" "F.Paste")
			(net "GND")
		)
		(zone
			(layer "F.Cu")
			(hatch none 0.5)
			(connect_pads
				(clearance 0)
			)
			(min_thickness 0.25)
			(keepout
				(tracks allowed)
				(vias not_allowed)
				(pads allowed)
				(copperpour not_allowed)
				(footprints allowed)
			)
			(placement
				(enabled no)
				(sheetname "")
			)
			(fill
				(thermal_gap 0.5)
				(thermal_bridge_width 0.5)
				(island_removal_mode 0)
			)
			(polygon
				(pts
					(xy 31.781496 -68.969382) (xy 32.162496 -68.969382) (xy 32.162496 -69.477382) (xy 31.781496 -69.477382)
				)
			)
		)
		(zone
			(layer "F.Cu")
			(hatch none 0.5)
			(connect_pads
				(clearance 0)
			)
			(min_thickness 0.25)
			(keepout
				(tracks not_allowed)
				(vias allowed)
				(pads allowed)
				(copperpour not_allowed)
				(footprints allowed)
			)
			(placement
				(enabled no)
				(sheetname "")
			)
			(fill
				(thermal_gap 0.5)
				(thermal_bridge_width 0.5)
				(island_removal_mode 0)
			)
			(polygon
				(pts
					(xy 31.781496 -68.969382) (xy 32.162496 -68.969382) (xy 32.162496 -69.477382) (xy 31.781496 -69.477382)
				)
			)
		)
	)
	(footprint ""
		(layer "F.Cu")
		(at 21.222462 -57.0992 180)
		(property "Reference" "EU1E3"
			(at 2.299462 -1.49987 0)
			(unlocked yes)
			(layer "F.SilkS")
			(effects
				(font
					(size 0.7874 0.5842)
					(thickness 0.1524)
				)
			)
		)
		(property "Value" ""
			(at 0 0 180)
			(layer "F.Fab")
			(effects
				(font
					(size 1.27 1.27)
				)
			)
		)
		(duplicate_pad_numbers_are_jumpers no)
		(fp_line
			(start 4.8006 4.5593)
			(end 4.8006 4.445254)
			(stroke
				(width 0.1524)
				(type default)
			)
			(layer "F.SilkS")
		)
		(fp_line
			(start 4.8006 -0.7493)
			(end 4.8006 -0.635254)
			(stroke
				(width 0.1524)
				(type default)
			)
			(layer "F.SilkS")
		)
		(fp_line
			(start 0.4064 4.5593)
			(end 4.8006 4.5593)
			(stroke
				(width 0.1524)
				(type default)
			)
			(layer "F.SilkS")
		)
		(fp_line
			(start 0.4064 4.445254)
			(end 0.4064 4.5593)
			(stroke
				(width 0.1524)
				(type default)
			)
			(layer "F.SilkS")
		)
		(fp_line
			(start 0.4064 -0.635254)
			(end 0.4064 -0.7493)
			(stroke
				(width 0.1524)
				(type default)
			)
			(layer "F.SilkS")
		)
		(fp_line
			(start 0.4064 -0.7493)
			(end 4.8006 -0.7493)
			(stroke
				(width 0.1524)
				(type default)
			)
			(layer "F.SilkS")
		)
		(fp_circle
			(center -1.279906 -0.230378)
			(end -1.406906 -0.230378)
			(stroke
				(width 0.254)
				(type default)
			)
			(fill no)
			(layer "F.SilkS")
		)
		(fp_rect
			(start 4.8006 -0.7493)
			(end 0.4064 4.5593)
			(stroke
				(width 0)
				(type default)
			)
			(fill no)
			(layer "F.CrtYd")
		)
		(fp_line
			(start 4.8006 4.5593)
			(end 0.4064 4.5593)
			(stroke
				(width 0.1)
				(type default)
			)
			(layer "F.Fab")
		)
		(fp_line
			(start 4.8006 -0.7493)
			(end 4.8006 4.5593)
			(stroke
				(width 0.1)
				(type default)
			)
			(layer "F.Fab")
		)
		(fp_line
			(start 0.4064 4.5593)
			(end 0.4064 -0.7493)
			(stroke
				(width 0.1)
				(type default)
			)
			(layer "F.Fab")
		)
		(fp_line
			(start 0.4064 -0.7493)
			(end 4.8006 -0.7493)
			(stroke
				(width 0.1)
				(type default)
			)
			(layer "F.Fab")
		)
		(fp_circle
			(center -1.076706 -0.704342)
			(end -1.203706 -0.704342)
			(stroke
				(width 0.635)
				(type default)
			)
			(fill no)
			(layer "F.Fab")
		)
		(pad "1" smd rect
			(at 0 0 180)
			(size 1.651 0.508)
			(layers "F.Cu" "F.Mask" "F.Paste")
			(net "P12V_STBY")
		)
		(pad "2" smd rect
			(at 0 1.27 180)
			(size 1.651 0.508)
			(layers "F.Cu" "F.Mask" "F.Paste")
			(net "P12V_STBY")
		)
		(pad "3" smd rect
			(at 0 2.54 180)
			(size 1.651 0.508)
			(layers "F.Cu" "F.Mask" "F.Paste")
			(net "P12V_STBY")
		)
		(pad "4" smd rect
			(at 0 3.81 180)
			(size 1.651 0.508)
			(layers "F.Cu" "F.Mask" "F.Paste")
			(net "A_HSC_GATE1_R")
		)
		(pad "5" smd custom
			(at 3.937 1.905 180)
			(size 1.04775 1.04775)
			(layers "F.Cu" "F.Mask" "F.Paste")
			(net "P12V_MB0_SW")
			(options
				(clearance outline)
				(anchor circle)
			)
			(primitives
				(gr_poly
					(pts
						(xy -2.0955 -1.651) (xy -2.0955 1.651) (xy 0.4445 1.651) (xy 0.4445 2.2098) (xy 2.0955 2.2098)
						(xy 2.0955 -2.2098) (xy 0.4445 -2.2098) (xy 0.4445 -1.651)
					)
					(width 0)
					(fill yes)
				)
			)
		)
	)
)
